(kicad_pcb
	(version 20260206)
	(generator "pcbnew")
	(generator_version "10.0")
	(general
		(thickness 1.6)
		(legacy_teardrops no)
	)
	(paper "A4")
	(title_block
		(title "04192023_DAF0TMB3IC0_F0TG_MB_C_brd_V02_OCP.brd")
		(comment 1 "Grand Teton / footprints 5196-5202 of 8354")
	)
	(layers
		(0 "F.Cu" signal "TOP")
		(4 "In1.Cu" signal "GND")
		(6 "In2.Cu" signal "IN1")
		(8 "In3.Cu" signal "GND1")
		(10 "In4.Cu" signal "IN2")
		(12 "In5.Cu" signal "GND2")
		(14 "In6.Cu" signal "IN3")
		(16 "In7.Cu" signal "GND3")
		(18 "In8.Cu" signal "VCC")
		(20 "In9.Cu" signal "VCC1")
		(22 "In10.Cu" signal "GND4")
		(24 "In11.Cu" signal "IN4")
		(26 "In12.Cu" signal "GND5")
		(28 "In13.Cu" signal "IN5")
		(30 "In14.Cu" signal "GND6")
		(32 "In15.Cu" signal "IN6")
		(34 "In16.Cu" signal "GND7")
		(2 "B.Cu" signal "BOTTOM")
		(9 "F.Adhes" user "F.Adhesive")
		(11 "B.Adhes" user "B.Adhesive")
		(13 "F.Paste" user "Package Geometry/Pastemask Top")
		(15 "B.Paste" user "Package Geometry/Pastemask Bottom")
		(5 "F.SilkS" user "Ref Des/Silkscreen Top")
		(7 "B.SilkS" user "Ref Des/Silkscreen Bottom")
		(1 "F.Mask" user "Board Geometry/Soldermask Top")
		(3 "B.Mask" user "Board Geometry/Soldermask Bottom")
		(17 "Dwgs.User" user "User.Drawings")
		(19 "Cmts.User" user "User.Comments")
		(21 "Eco1.User" user "User.Eco1")
		(23 "Eco2.User" user "User.Eco2")
		(25 "Edge.Cuts" user "Board Geometry/Outline")
		(27 "Margin" user)
		(31 "F.CrtYd" user "Package Geometry/Place Bound Top")
		(29 "B.CrtYd" user "Package Geometry/Place Bound Bottom")
		(35 "F.Fab" user "Ref Des/Assembly Top")
		(33 "B.Fab" user "Ref Des/Assembly Bottom")
	)
	(footprint ""
		(layer "B.Cu")
		(at 48.618902 -425.275248)
		(property "Reference" "Q72"
			(at 0.318008 -1.866138 0)
			(unlocked yes)
			(layer "B.SilkS")
			(effects
				(font
					(size 0.7874 0.5842)
					(thickness 0.1524)
				)
				(justify left mirror)
			)
		)
		(property "Value" ""
			(at 0 0 0)
			(layer "B.Fab")
			(effects
				(font
					(size 1.27 1.27)
				)
				(justify mirror)
			)
		)
		(duplicate_pad_numbers_are_jumpers no)
		(fp_line
			(start -1.332738 -1.100074)
			(end -1.332738 1.100074)
			(stroke
				(width 0.1524)
				(type default)
			)
			(layer "B.SilkS")
		)
		(fp_line
			(start -1.332738 1.100074)
			(end 1.332738 1.100074)
			(stroke
				(width 0.1524)
				(type default)
			)
			(layer "B.SilkS")
		)
		(fp_line
			(start -0.4826 -1.100074)
			(end -1.332738 -1.100074)
			(stroke
				(width 0.1524)
				(type default)
			)
			(layer "B.SilkS")
		)
		(fp_line
			(start 0 -0.541274)
			(end -0.4826 -1.100074)
			(stroke
				(width 0.1524)
				(type default)
			)
			(layer "B.SilkS")
		)
		(fp_line
			(start 0.4826 -1.100074)
			(end 0 -0.541274)
			(stroke
				(width 0.1524)
				(type default)
			)
			(layer "B.SilkS")
		)
		(fp_line
			(start 1.332738 -1.100074)
			(end 0.4826 -1.100074)
			(stroke
				(width 0.1524)
				(type default)
			)
			(layer "B.SilkS")
		)
		(fp_line
			(start 1.332738 1.100074)
			(end 1.332738 -1.100074)
			(stroke
				(width 0.1524)
				(type default)
			)
			(layer "B.SilkS")
		)
		(fp_poly
			(pts
				(xy 1.62814 -1.297686) (xy 2.372614 -1.545844) (xy 1.876298 -2.042414)
			)
			(stroke
				(width 0)
				(type default)
			)
			(fill yes)
			(layer "B.SilkS")
		)
		(fp_line
			(start -0.674878 -1.100074)
			(end -0.674878 1.100074)
			(stroke
				(width 0.1)
				(type default)
			)
			(layer "B.Fab")
		)
		(fp_line
			(start -0.674878 1.100074)
			(end 0.674878 1.100074)
			(stroke
				(width 0.1)
				(type default)
			)
			(layer "B.Fab")
		)
		(fp_line
			(start 0.674878 -1.100074)
			(end -0.674878 -1.100074)
			(stroke
				(width 0.1)
				(type default)
			)
			(layer "B.Fab")
		)
		(fp_line
			(start 0.674878 1.100074)
			(end 0.674878 -1.100074)
			(stroke
				(width 0.1)
				(type default)
			)
			(layer "B.Fab")
		)
		(fp_poly
			(pts
				(xy 2.2352 -0.298958) (xy 2.2352 -1.001014) (xy 1.533144 -0.649986)
			)
			(stroke
				(width 0)
				(type default)
			)
			(fill yes)
			(layer "B.Fab")
		)
		(pad "1" smd rect
			(at 0.94996 -0.649986 90)
			(size 0.4318 0.508)
			(layers "B.Cu" "B.Mask" "B.Paste")
			(net "GND")
		)
		(pad "2" smd rect
			(at 0.94996 0 90)
			(size 0.4318 0.508)
			(layers "B.Cu" "B.Mask" "B.Paste")
			(net "FM_GPU_PWRGD")
		)
		(pad "3" smd rect
			(at 0.94996 0.649986 90)
			(size 0.4318 0.508)
			(layers "B.Cu" "B.Mask" "B.Paste")
			(net "FM_GPU_PWRGD_ISO")
		)
		(pad "4" smd rect
			(at -0.94996 0.649986 90)
			(size 0.4318 0.508)
			(layers "B.Cu" "B.Mask" "B.Paste")
			(net "GND")
		)
		(pad "5" smd rect
			(at -0.94996 0 90)
			(size 0.4318 0.508)
			(layers "B.Cu" "B.Mask" "B.Paste")
			(net "FM_GPU_PWRGD_N")
		)
		(pad "6" smd rect
			(at -0.94996 -0.649986 90)
			(size 0.4318 0.508)
			(layers "B.Cu" "B.Mask" "B.Paste")
			(net "FM_GPU_PWRGD_N")
		)
	)
	(footprint ""
		(layer "B.Cu")
		(at 305.300126 -416.899344 90)
		(property "Reference" "C6534"
			(at 0 0 90)
			(layer "B.SilkS")
			(hide yes)
			(effects
				(font
					(size 1.27 1.27)
				)
				(justify mirror)
			)
		)
		(property "Value" ""
			(at 0 0 90)
			(layer "B.Fab")
			(effects
				(font
					(size 1.27 1.27)
				)
				(justify mirror)
			)
		)
		(duplicate_pad_numbers_are_jumpers no)
		(fp_line
			(start 0.299974 -0.150114)
			(end -0.299974 -0.150114)
			(stroke
				(width 0.1)
				(type default)
			)
			(layer "B.Fab")
		)
		(fp_line
			(start -0.299974 -0.150114)
			(end -0.299974 0.150114)
			(stroke
				(width 0.1)
				(type default)
			)
			(layer "B.Fab")
		)
		(fp_line
			(start 0.299974 0.150114)
			(end 0.299974 -0.150114)
			(stroke
				(width 0.1)
				(type default)
			)
			(layer "B.Fab")
		)
		(fp_line
			(start -0.299974 0.150114)
			(end 0.299974 0.150114)
			(stroke
				(width 0.1)
				(type default)
			)
			(layer "B.Fab")
		)
		(pad "1" smd rect
			(at 0.2667 0 270)
			(size 0.3048 0.381)
			(layers "B.Cu" "B.Mask" "B.Paste")
			(net "P5E_CPU0_P1_TX_BUF_C_DN<0>")
		)
		(pad "2" smd rect
			(at -0.2667 0 270)
			(size 0.3048 0.381)
			(layers "B.Cu" "B.Mask" "B.Paste")
			(net "P5E_CPU0_P1_TX_BUF_DN<0>")
		)
	)
	(footprint ""
		(layer "B.Cu")
		(at 82.014314 -335.060798 90)
		(property "Reference" "PC380_2"
			(at 0 0 90)
			(layer "B.SilkS")
			(hide yes)
			(effects
				(font
					(size 1.27 1.27)
				)
				(justify mirror)
			)
		)
		(property "Value" ""
			(at 0 0 90)
			(layer "B.Fab")
			(effects
				(font
					(size 1.27 1.27)
				)
				(justify mirror)
			)
		)
		(duplicate_pad_numbers_are_jumpers no)
		(fp_line
			(start 1.524 -0.762)
			(end -1.524 -0.762)
			(stroke
				(width 0.1524)
				(type default)
			)
			(layer "B.SilkS")
		)
		(fp_line
			(start -1.524 -0.762)
			(end -1.524 0.762)
			(stroke
				(width 0.1524)
				(type default)
			)
			(layer "B.SilkS")
		)
		(fp_line
			(start 1.524 0.762)
			(end 1.524 -0.762)
			(stroke
				(width 0.1524)
				(type default)
			)
			(layer "B.SilkS")
		)
		(fp_line
			(start -1.524 0.762)
			(end 1.524 0.762)
			(stroke
				(width 0.1524)
				(type default)
			)
			(layer "B.SilkS")
		)
		(fp_line
			(start 1.1049 -0.724916)
			(end 1.1049 0.724916)
			(stroke
				(width 0.1)
				(type default)
			)
			(layer "B.Fab")
		)
		(fp_line
			(start -1.1049 -0.724916)
			(end 1.1049 -0.724916)
			(stroke
				(width 0.1)
				(type default)
			)
			(layer "B.Fab")
		)
		(fp_line
			(start 1.1049 0.724916)
			(end -1.1049 0.724916)
			(stroke
				(width 0.1)
				(type default)
			)
			(layer "B.Fab")
		)
		(fp_line
			(start -1.1049 0.724916)
			(end -1.1049 -0.724916)
			(stroke
				(width 0.1)
				(type default)
			)
			(layer "B.Fab")
		)
		(pad "1" smd rect
			(at 0.889 0 90)
			(size 1.016 1.27)
			(layers "B.Cu" "B.Mask" "B.Paste")
			(net "SW_P12V_AUX_PVDDCR_CPU1_P1_FLT")
		)
		(pad "2" smd rect
			(at -0.889 0 90)
			(size 1.016 1.27)
			(layers "B.Cu" "B.Mask" "B.Paste")
			(net "GND")
		)
	)
	(footprint ""
		(layer "B.Cu")
		(at 305.034696 -349.381572 -90)
		(property "Reference" "PR91"
			(at 0 0 90)
			(layer "B.SilkS")
			(hide yes)
			(effects
				(font
					(size 1.27 1.27)
				)
				(justify mirror)
			)
		)
		(property "Value" ""
			(at 0 0 90)
			(layer "B.Fab")
			(effects
				(font
					(size 1.27 1.27)
				)
				(justify mirror)
			)
		)
		(duplicate_pad_numbers_are_jumpers no)
		(fp_line
			(start -0.7874 0.4064)
			(end 0.7874 0.4064)
			(stroke
				(width 0.1524)
				(type default)
			)
			(layer "B.SilkS")
		)
		(fp_line
			(start 0.7874 0.4064)
			(end 0.7874 -0.4064)
			(stroke
				(width 0.1524)
				(type default)
			)
			(layer "B.SilkS")
		)
		(fp_line
			(start -0.7874 -0.4064)
			(end -0.7874 0.4064)
			(stroke
				(width 0.1524)
				(type default)
			)
			(layer "B.SilkS")
		)
		(fp_line
			(start 0.7874 -0.4064)
			(end -0.7874 -0.4064)
			(stroke
				(width 0.1524)
				(type default)
			)
			(layer "B.SilkS")
		)
		(fp_line
			(start -0.67945 0.3048)
			(end -0.120396 0.3048)
			(stroke
				(width 0.1)
				(type default)
			)
			(layer "B.Fab")
		)
		(fp_line
			(start -0.120396 0.3048)
			(end -0.120396 0.2794)
			(stroke
				(width 0.1)
				(type default)
			)
			(layer "B.Fab")
		)
		(fp_line
			(start 0.12065 0.3048)
			(end 0.67945 0.3048)
			(stroke
				(width 0.1)
				(type default)
			)
			(layer "B.Fab")
		)
		(fp_line
			(start 0.67945 0.3048)
			(end 0.67945 -0.305054)
			(stroke
				(width 0.1)
				(type default)
			)
			(layer "B.Fab")
		)
		(fp_line
			(start -0.120396 0.2794)
			(end 0.12065 0.2794)
			(stroke
				(width 0.1)
				(type default)
			)
			(layer "B.Fab")
		)
		(fp_line
			(start 0.12065 0.2794)
			(end 0.12065 0.3048)
			(stroke
				(width 0.1)
				(type default)
			)
			(layer "B.Fab")
		)
		(fp_line
			(start -0.12065 -0.2794)
			(end -0.12065 -0.3048)
			(stroke
				(width 0.1)
				(type default)
			)
			(layer "B.Fab")
		)
		(fp_line
			(start 0.12065 -0.2794)
			(end -0.12065 -0.2794)
			(stroke
				(width 0.1)
				(type default)
			)
			(layer "B.Fab")
		)
		(fp_line
			(start -0.67945 -0.3048)
			(end -0.67945 0.3048)
			(stroke
				(width 0.1)
				(type default)
			)
			(layer "B.Fab")
		)
		(fp_line
			(start -0.12065 -0.3048)
			(end -0.67945 -0.3048)
			(stroke
				(width 0.1)
				(type default)
			)
			(layer "B.Fab")
		)
		(fp_line
			(start 0.12065 -0.305054)
			(end 0.12065 -0.2794)
			(stroke
				(width 0.1)
				(type default)
			)
			(layer "B.Fab")
		)
		(fp_line
			(start 0.67945 -0.305054)
			(end 0.12065 -0.305054)
			(stroke
				(width 0.1)
				(type default)
			)
			(layer "B.Fab")
		)
		(pad "1" smd circle
			(at 0.40005 0 90)
			(size 0 0)
			(layers "B.Cu" "B.Mask" "B.Paste")
			(net "PVDDCR_CPU1_P0_VOS4")
		)
		(pad "2" smd circle
			(at -0.40005 0 90)
			(size 0 0)
			(layers "B.Cu" "B.Mask" "B.Paste")
			(net "PVDDCR_CPU1_P0")
		)
	)
	(footprint ""
		(layer "B.Cu")
		(at 192.287652 -80.20304 -90)
		(property "Reference" "C640"
			(at 0 0 90)
			(layer "B.SilkS")
			(hide yes)
			(effects
				(font
					(size 1.27 1.27)
				)
				(justify mirror)
			)
		)
		(property "Value" ""
			(at 0 0 90)
			(layer "B.Fab")
			(effects
				(font
					(size 1.27 1.27)
				)
				(justify mirror)
			)
		)
		(duplicate_pad_numbers_are_jumpers no)
		(fp_line
			(start -0.7874 0.4064)
			(end 0.7874 0.4064)
			(stroke
				(width 0.1524)
				(type default)
			)
			(layer "B.SilkS")
		)
		(fp_line
			(start 0.7874 0.4064)
			(end 0.7874 -0.4064)
			(stroke
				(width 0.1524)
				(type default)
			)
			(layer "B.SilkS")
		)
		(fp_line
			(start -0.7874 -0.4064)
			(end -0.7874 0.4064)
			(stroke
				(width 0.1524)
				(type default)
			)
			(layer "B.SilkS")
		)
		(fp_line
			(start 0.7874 -0.4064)
			(end -0.7874 -0.4064)
			(stroke
				(width 0.1524)
				(type default)
			)
			(layer "B.SilkS")
		)
		(fp_line
			(start -0.67945 0.3048)
			(end -0.120396 0.3048)
			(stroke
				(width 0.1)
				(type default)
			)
			(layer "B.Fab")
		)
		(fp_line
			(start -0.120396 0.3048)
			(end -0.120396 0.2794)
			(stroke
				(width 0.1)
				(type default)
			)
			(layer "B.Fab")
		)
		(fp_line
			(start 0.12065 0.3048)
			(end 0.67945 0.3048)
			(stroke
				(width 0.1)
				(type default)
			)
			(layer "B.Fab")
		)
		(fp_line
			(start 0.67945 0.3048)
			(end 0.67945 -0.305054)
			(stroke
				(width 0.1)
				(type default)
			)
			(layer "B.Fab")
		)
		(fp_line
			(start -0.120396 0.2794)
			(end 0.12065 0.2794)
			(stroke
				(width 0.1)
				(type default)
			)
			(layer "B.Fab")
		)
		(fp_line
			(start 0.12065 0.2794)
			(end 0.12065 0.3048)
			(stroke
				(width 0.1)
				(type default)
			)
			(layer "B.Fab")
		)
		(fp_line
			(start -0.12065 -0.2794)
			(end -0.12065 -0.3048)
			(stroke
				(width 0.1)
				(type default)
			)
			(layer "B.Fab")
		)
		(fp_line
			(start 0.12065 -0.2794)
			(end -0.12065 -0.2794)
			(stroke
				(width 0.1)
				(type default)
			)
			(layer "B.Fab")
		)
		(fp_line
			(start -0.67945 -0.3048)
			(end -0.67945 0.3048)
			(stroke
				(width 0.1)
				(type default)
			)
			(layer "B.Fab")
		)
		(fp_line
			(start -0.12065 -0.3048)
			(end -0.67945 -0.3048)
			(stroke
				(width 0.1)
				(type default)
			)
			(layer "B.Fab")
		)
		(fp_line
			(start 0.12065 -0.305054)
			(end 0.12065 -0.2794)
			(stroke
				(width 0.1)
				(type default)
			)
			(layer "B.Fab")
		)
		(fp_line
			(start 0.67945 -0.305054)
			(end 0.12065 -0.305054)
			(stroke
				(width 0.1)
				(type default)
			)
			(layer "B.Fab")
		)
		(pad "1" smd circle
			(at 0.40005 0 90)
			(size 0 0)
			(layers "B.Cu" "B.Mask" "B.Paste")
			(net "P3V3_AUX")
		)
		(pad "2" smd circle
			(at -0.40005 0 90)
			(size 0 0)
			(layers "B.Cu" "B.Mask" "B.Paste")
			(net "GND")
		)
	)
	(footprint ""
		(layer "B.Cu")
		(at 236.20095 -51.209448)
		(property "Reference" "R10296"
			(at 0 0 0)
			(layer "B.SilkS")
			(hide yes)
			(effects
				(font
					(size 1.27 1.27)
				)
				(justify mirror)
			)
		)
		(property "Value" ""
			(at 0 0 0)
			(layer "B.Fab")
			(effects
				(font
					(size 1.27 1.27)
				)
				(justify mirror)
			)
		)
		(duplicate_pad_numbers_are_jumpers no)
		(fp_line
			(start -0.7874 -0.4064)
			(end -0.7874 0.4064)
			(stroke
				(width 0.1524)
				(type default)
			)
			(layer "B.SilkS")
		)
		(fp_line
			(start -0.7874 0.4064)
			(end 0.7874 0.4064)
			(stroke
				(width 0.1524)
				(type default)
			)
			(layer "B.SilkS")
		)
		(fp_line
			(start 0.7874 -0.4064)
			(end -0.7874 -0.4064)
			(stroke
				(width 0.1524)
				(type default)
			)
			(layer "B.SilkS")
		)
		(fp_line
			(start 0.7874 0.4064)
			(end 0.7874 -0.4064)
			(stroke
				(width 0.1524)
				(type default)
			)
			(layer "B.SilkS")
		)
		(fp_line
			(start -0.67945 -0.3048)
			(end -0.67945 0.3048)
			(stroke
				(width 0.1)
				(type default)
			)
			(layer "B.Fab")
		)
		(fp_line
			(start -0.67945 0.3048)
			(end -0.120396 0.3048)
			(stroke
				(width 0.1)
				(type default)
			)
			(layer "B.Fab")
		)
		(fp_line
			(start -0.12065 -0.3048)
			(end -0.67945 -0.3048)
			(stroke
				(width 0.1)
				(type default)
			)
			(layer "B.Fab")
		)
		(fp_line
			(start -0.12065 -0.2794)
			(end -0.12065 -0.3048)
			(stroke
				(width 0.1)
				(type default)
			)
			(layer "B.Fab")
		)
		(fp_line
			(start -0.120396 0.2794)
			(end 0.12065 0.2794)
			(stroke
				(width 0.1)
				(type default)
			)
			(layer "B.Fab")
		)
		(fp_line
			(start -0.120396 0.3048)
			(end -0.120396 0.2794)
			(stroke
				(width 0.1)
				(type default)
			)
			(layer "B.Fab")
		)
		(fp_line
			(start 0.12065 -0.305054)
			(end 0.12065 -0.2794)
			(stroke
				(width 0.1)
				(type default)
			)
			(layer "B.Fab")
		)
		(fp_line
			(start 0.12065 -0.2794)
			(end -0.12065 -0.2794)
			(stroke
				(width 0.1)
				(type default)
			)
			(layer "B.Fab")
		)
		(fp_line
			(start 0.12065 0.2794)
			(end 0.12065 0.3048)
			(stroke
				(width 0.1)
				(type default)
			)
			(layer "B.Fab")
		)
		(fp_line
			(start 0.12065 0.3048)
			(end 0.67945 0.3048)
			(stroke
				(width 0.1)
				(type default)
			)
			(layer "B.Fab")
		)
		(fp_line
			(start 0.67945 -0.305054)
			(end 0.12065 -0.305054)
			(stroke
				(width 0.1)
				(type default)
			)
			(layer "B.Fab")
		)
		(fp_line
			(start 0.67945 0.3048)
			(end 0.67945 -0.305054)
			(stroke
				(width 0.1)
				(type default)
			)
			(layer "B.Fab")
		)
		(pad "1" smd circle
			(at 0.40005 0 180)
			(size 0 0)
			(layers "B.Cu" "B.Mask" "B.Paste")
			(net "E1S_0_PWRDIS")
		)
		(pad "2" smd circle
			(at -0.40005 0 180)
			(size 0 0)
			(layers "B.Cu" "B.Mask" "B.Paste")
			(net "GND")
		)
	)
	(footprint ""
		(layer "B.Cu")
		(at 20.919186 -195.926964 180)
		(property "Reference" "R1704"
			(at 0 0 0)
			(layer "B.SilkS")
			(hide yes)
			(effects
				(font
					(size 1.27 1.27)
				)
				(justify mirror)
			)
		)
		(property "Value" ""
			(at 0 0 0)
			(layer "B.Fab")
			(effects
				(font
					(size 1.27 1.27)
				)
				(justify mirror)
			)
		)
		(duplicate_pad_numbers_are_jumpers no)
		(fp_line
			(start 0.7874 0.4064)
			(end 0.7874 -0.4064)
			(stroke
				(width 0.1524)
				(type default)
			)
			(layer "B.SilkS")
		)
		(fp_line
			(start 0.7874 -0.4064)
			(end -0.7874 -0.4064)
			(stroke
				(width 0.1524)
				(type default)
			)
			(layer "B.SilkS")
		)
		(fp_line
			(start -0.7874 0.4064)
			(end 0.7874 0.4064)
			(stroke
				(width 0.1524)
				(type default)
			)
			(layer "B.SilkS")
		)
		(fp_line
			(start -0.7874 -0.4064)
			(end -0.7874 0.4064)
			(stroke
				(width 0.1524)
				(type default)
			)
			(layer "B.SilkS")
		)
		(fp_line
			(start 0.67945 0.3048)
			(end 0.67945 -0.305054)
			(stroke
				(width 0.1)
				(type default)
			)
			(layer "B.Fab")
		)
		(fp_line
			(start 0.67945 -0.305054)
			(end 0.12065 -0.305054)
			(stroke
				(width 0.1)
				(type default)
			)
			(layer "B.Fab")
		)
		(fp_line
			(start 0.12065 0.3048)
			(end 0.67945 0.3048)
			(stroke
				(width 0.1)
				(type default)
			)
			(layer "B.Fab")
		)
		(fp_line
			(start 0.12065 0.2794)
			(end 0.12065 0.3048)
			(stroke
				(width 0.1)
				(type default)
			)
			(layer "B.Fab")
		)
		(fp_line
			(start 0.12065 -0.2794)
			(end -0.12065 -0.2794)
			(stroke
				(width 0.1)
				(type default)
			)
			(layer "B.Fab")
		)
		(fp_line
			(start 0.12065 -0.305054)
			(end 0.12065 -0.2794)
			(stroke
				(width 0.1)
				(type default)
			)
			(layer "B.Fab")
		)
		(fp_line
			(start -0.120396 0.3048)
			(end -0.120396 0.2794)
			(stroke
				(width 0.1)
				(type default)
			)
			(layer "B.Fab")
		)
		(fp_line
			(start -0.120396 0.2794)
			(end 0.12065 0.2794)
			(stroke
				(width 0.1)
				(type default)
			)
			(layer "B.Fab")
		)
		(fp_line
			(start -0.12065 -0.2794)
			(end -0.12065 -0.3048)
			(stroke
				(width 0.1)
				(type default)
			)
			(layer "B.Fab")
		)
		(fp_line
			(start -0.12065 -0.3048)
			(end -0.67945 -0.3048)
			(stroke
				(width 0.1)
				(type default)
			)
			(layer "B.Fab")
		)
		(fp_line
			(start -0.67945 0.3048)
			(end -0.120396 0.3048)
			(stroke
				(width 0.1)
				(type default)
			)
			(layer "B.Fab")
		)
		(fp_line
			(start -0.67945 -0.3048)
			(end -0.67945 0.3048)
			(stroke
				(width 0.1)
				(type default)
			)
			(layer "B.Fab")
		)
		(pad "1" smd circle
			(at 0.40005 0)
			(size 0 0)
			(layers "B.Cu" "B.Mask" "B.Paste")
			(net "I3C_SPD_DDRAF_CPU1_SDA")
		)
		(pad "2" smd circle
			(at -0.40005 0)
			(size 0 0)
			(layers "B.Cu" "B.Mask" "B.Paste")
			(net "I3C_SPD_DDRF_CPU1_SDA")
		)
	)
)
